(kicad_pcb
	(version 20260206)
	(generator "pcbnew")
	(generator_version "10.0")
	(general
		(thickness 1.6)
		(legacy_teardrops no)
	)
	(paper "A4")
	(title_block
		(title "01162023_DA0F0TEBIF0_F0T_Expander_BD_F_brd_V02_OCP.brd")
		(comment 1 "Grand Teton / footprints 7525-7532 of 9728")
	)
	(layers
		(0 "F.Cu" signal "TOP")
		(4 "In1.Cu" signal "GND")
		(6 "In2.Cu" signal "VCC")
		(8 "In3.Cu" signal "VCC1")
		(10 "In4.Cu" signal "GND1")
		(12 "In5.Cu" signal "IN1")
		(14 "In6.Cu" signal "GND2")
		(16 "In7.Cu" signal "IN2")
		(18 "In8.Cu" signal "GND3")
		(20 "In9.Cu" signal "IN3")
		(22 "In10.Cu" signal "GND4")
		(24 "In11.Cu" signal "IN4")
		(26 "In12.Cu" signal "GND5")
		(28 "In13.Cu" signal "IN5")
		(30 "In14.Cu" signal "GND6")
		(32 "In15.Cu" signal "IN6")
		(34 "In16.Cu" signal "GND7")
		(2 "B.Cu" signal "BOTTOM")
		(9 "F.Adhes" user "F.Adhesive")
		(11 "B.Adhes" user "B.Adhesive")
		(13 "F.Paste" user "Package Geometry/Pastemask Top")
		(15 "B.Paste" user "Package Geometry/Pastemask Bottom")
		(5 "F.SilkS" user "Ref Des/Silkscreen Top")
		(7 "B.SilkS" user "Ref Des/Silkscreen Bottom")
		(1 "F.Mask" user "Board Geometry/Soldermask Top")
		(3 "B.Mask" user "Board Geometry/Soldermask Bottom")
		(17 "Dwgs.User" user "User.Drawings")
		(19 "Cmts.User" user "User.Comments")
		(21 "Eco1.User" user "User.Eco1")
		(23 "Eco2.User" user "User.Eco2")
		(25 "Edge.Cuts" user "Board Geometry/Outline")
		(27 "Margin" user)
		(31 "F.CrtYd" user "Package Geometry/Place Bound Top")
		(29 "B.CrtYd" user "Package Geometry/Place Bound Bottom")
		(35 "F.Fab" user "Ref Des/Assembly Top")
		(33 "B.Fab" user "Ref Des/Assembly Bottom")
	)
	(footprint ""
		(layer "B.Cu")
		(at 116.788184 -316.017402 180)
		(property "Reference" "C4211"
			(at 0 0 0)
			(layer "B.SilkS")
			(hide yes)
			(effects
				(font
					(size 1.27 1.27)
				)
				(justify mirror)
			)
		)
		(property "Value" ""
			(at 0 0 0)
			(layer "B.Fab")
			(effects
				(font
					(size 1.27 1.27)
				)
				(justify mirror)
			)
		)
		(duplicate_pad_numbers_are_jumpers no)
		(fp_line
			(start 0.299974 0.150114)
			(end 0.299974 -0.150114)
			(stroke
				(width 0.1)
				(type default)
			)
			(layer "B.Fab")
		)
		(fp_line
			(start 0.299974 -0.150114)
			(end -0.299974 -0.150114)
			(stroke
				(width 0.1)
				(type default)
			)
			(layer "B.Fab")
		)
		(fp_line
			(start -0.299974 0.150114)
			(end 0.299974 0.150114)
			(stroke
				(width 0.1)
				(type default)
			)
			(layer "B.Fab")
		)
		(fp_line
			(start -0.299974 -0.150114)
			(end -0.299974 0.150114)
			(stroke
				(width 0.1)
				(type default)
			)
			(layer "B.Fab")
		)
		(pad "1" smd rect
			(at 0.2667 0)
			(size 0.3048 0.381)
			(layers "B.Cu" "B.Mask" "B.Paste")
			(net "P0V8_SERDES_VDDA_PEX0")
		)
		(pad "2" smd rect
			(at -0.2667 0)
			(size 0.3048 0.381)
			(layers "B.Cu" "B.Mask" "B.Paste")
			(net "GND")
		)
	)
	(footprint ""
		(layer "B.Cu")
		(at 77.541882 -102.088696 180)
		(property "Reference" "R68"
			(at 0 0 0)
			(layer "B.SilkS")
			(hide yes)
			(effects
				(font
					(size 1.27 1.27)
				)
				(justify mirror)
			)
		)
		(property "Value" ""
			(at 0 0 0)
			(layer "B.Fab")
			(effects
				(font
					(size 1.27 1.27)
				)
				(justify mirror)
			)
		)
		(duplicate_pad_numbers_are_jumpers no)
		(fp_line
			(start 0.7874 0.4064)
			(end 0.7874 -0.4064)
			(stroke
				(width 0.1524)
				(type default)
			)
			(layer "B.SilkS")
		)
		(fp_line
			(start 0.7874 -0.4064)
			(end -0.7874 -0.4064)
			(stroke
				(width 0.1524)
				(type default)
			)
			(layer "B.SilkS")
		)
		(fp_line
			(start -0.7874 0.4064)
			(end 0.7874 0.4064)
			(stroke
				(width 0.1524)
				(type default)
			)
			(layer "B.SilkS")
		)
		(fp_line
			(start -0.7874 -0.4064)
			(end -0.7874 0.4064)
			(stroke
				(width 0.1524)
				(type default)
			)
			(layer "B.SilkS")
		)
		(fp_line
			(start 0.67945 0.3048)
			(end 0.67945 -0.305054)
			(stroke
				(width 0.1)
				(type default)
			)
			(layer "B.Fab")
		)
		(fp_line
			(start 0.67945 -0.305054)
			(end 0.12065 -0.305054)
			(stroke
				(width 0.1)
				(type default)
			)
			(layer "B.Fab")
		)
		(fp_line
			(start 0.12065 0.3048)
			(end 0.67945 0.3048)
			(stroke
				(width 0.1)
				(type default)
			)
			(layer "B.Fab")
		)
		(fp_line
			(start 0.12065 0.2794)
			(end 0.12065 0.3048)
			(stroke
				(width 0.1)
				(type default)
			)
			(layer "B.Fab")
		)
		(fp_line
			(start 0.12065 -0.2794)
			(end -0.12065 -0.2794)
			(stroke
				(width 0.1)
				(type default)
			)
			(layer "B.Fab")
		)
		(fp_line
			(start 0.12065 -0.305054)
			(end 0.12065 -0.2794)
			(stroke
				(width 0.1)
				(type default)
			)
			(layer "B.Fab")
		)
		(fp_line
			(start -0.120396 0.3048)
			(end -0.120396 0.2794)
			(stroke
				(width 0.1)
				(type default)
			)
			(layer "B.Fab")
		)
		(fp_line
			(start -0.120396 0.2794)
			(end 0.12065 0.2794)
			(stroke
				(width 0.1)
				(type default)
			)
			(layer "B.Fab")
		)
		(fp_line
			(start -0.12065 -0.2794)
			(end -0.12065 -0.3048)
			(stroke
				(width 0.1)
				(type default)
			)
			(layer "B.Fab")
		)
		(fp_line
			(start -0.12065 -0.3048)
			(end -0.67945 -0.3048)
			(stroke
				(width 0.1)
				(type default)
			)
			(layer "B.Fab")
		)
		(fp_line
			(start -0.67945 0.3048)
			(end -0.120396 0.3048)
			(stroke
				(width 0.1)
				(type default)
			)
			(layer "B.Fab")
		)
		(fp_line
			(start -0.67945 -0.3048)
			(end -0.67945 0.3048)
			(stroke
				(width 0.1)
				(type default)
			)
			(layer "B.Fab")
		)
		(pad "1" smd circle
			(at 0.40005 0)
			(size 0 0)
			(layers "B.Cu" "B.Mask" "B.Paste")
			(net "NCSI_NIC1_RXD1")
		)
		(pad "2" smd circle
			(at -0.40005 0)
			(size 0 0)
			(layers "B.Cu" "B.Mask" "B.Paste")
			(net "GND")
		)
	)
	(footprint ""
		(layer "B.Cu")
		(at 3.066796 -277.35403)
		(property "Reference" "C4235"
			(at 0 0 0)
			(layer "B.SilkS")
			(hide yes)
			(effects
				(font
					(size 1.27 1.27)
				)
				(justify mirror)
			)
		)
		(property "Value" ""
			(at 0 0 0)
			(layer "B.Fab")
			(effects
				(font
					(size 1.27 1.27)
				)
				(justify mirror)
			)
		)
		(duplicate_pad_numbers_are_jumpers no)
		(fp_line
			(start -1.2954 -0.5842)
			(end -1.2954 0.5842)
			(stroke
				(width 0.1524)
				(type default)
			)
			(layer "B.SilkS")
		)
		(fp_line
			(start -1.2954 0.5842)
			(end 1.2954 0.5842)
			(stroke
				(width 0.1524)
				(type default)
			)
			(layer "B.SilkS")
		)
		(fp_line
			(start 1.2954 -0.5842)
			(end -1.2954 -0.5842)
			(stroke
				(width 0.1524)
				(type default)
			)
			(layer "B.SilkS")
		)
		(fp_line
			(start 1.2954 0.5842)
			(end 1.2954 -0.5842)
			(stroke
				(width 0.1524)
				(type default)
			)
			(layer "B.SilkS")
		)
		(fp_line
			(start -1.1938 -0.4064)
			(end -1.1938 0.4064)
			(stroke
				(width 0.1)
				(type default)
			)
			(layer "B.Fab")
		)
		(fp_line
			(start -1.1938 0.4064)
			(end -0.8636 0.4064)
			(stroke
				(width 0.1)
				(type default)
			)
			(layer "B.Fab")
		)
		(fp_line
			(start -0.8636 -0.4572)
			(end -0.8636 -0.4064)
			(stroke
				(width 0.1)
				(type default)
			)
			(layer "B.Fab")
		)
		(fp_line
			(start -0.8636 -0.4064)
			(end -1.1938 -0.4064)
			(stroke
				(width 0.1)
				(type default)
			)
			(layer "B.Fab")
		)
		(fp_line
			(start -0.8636 0.4064)
			(end -0.8636 0.4572)
			(stroke
				(width 0.1)
				(type default)
			)
			(layer "B.Fab")
		)
		(fp_line
			(start -0.8636 0.4572)
			(end 0.8636 0.4572)
			(stroke
				(width 0.1)
				(type default)
			)
			(layer "B.Fab")
		)
		(fp_line
			(start 0.8636 -0.4572)
			(end -0.8636 -0.4572)
			(stroke
				(width 0.1)
				(type default)
			)
			(layer "B.Fab")
		)
		(fp_line
			(start 0.8636 -0.4064)
			(end 0.8636 -0.4572)
			(stroke
				(width 0.1)
				(type default)
			)
			(layer "B.Fab")
		)
		(fp_line
			(start 0.8636 0.4064)
			(end 1.1938 0.4064)
			(stroke
				(width 0.1)
				(type default)
			)
			(layer "B.Fab")
		)
		(fp_line
			(start 0.8636 0.4572)
			(end 0.8636 0.4064)
			(stroke
				(width 0.1)
				(type default)
			)
			(layer "B.Fab")
		)
		(fp_line
			(start 1.1938 -0.4064)
			(end 0.8636 -0.4064)
			(stroke
				(width 0.1)
				(type default)
			)
			(layer "B.Fab")
		)
		(fp_line
			(start 1.1938 0.4064)
			(end 1.1938 -0.4064)
			(stroke
				(width 0.1)
				(type default)
			)
			(layer "B.Fab")
		)
		(pad "1" smd rect
			(at 0.7366 0 270)
			(size 0.7112 0.8128)
			(layers "B.Cu" "B.Mask" "B.Paste")
			(net "P1V25_PEX0")
		)
		(pad "2" smd rect
			(at -0.7366 0 270)
			(size 0.7112 0.8128)
			(layers "B.Cu" "B.Mask" "B.Paste")
			(net "GND")
		)
	)
	(footprint ""
		(layer "B.Cu")
		(at 409.849828 -290.199826 90)
		(property "Reference" "C1975"
			(at 0 0 90)
			(layer "B.SilkS")
			(hide yes)
			(effects
				(font
					(size 1.27 1.27)
				)
				(justify mirror)
			)
		)
		(property "Value" ""
			(at 0 0 90)
			(layer "B.Fab")
			(effects
				(font
					(size 1.27 1.27)
				)
				(justify mirror)
			)
		)
		(duplicate_pad_numbers_are_jumpers no)
		(fp_line
			(start 0.299974 -0.150114)
			(end -0.299974 -0.150114)
			(stroke
				(width 0.1)
				(type default)
			)
			(layer "B.Fab")
		)
		(fp_line
			(start -0.299974 -0.150114)
			(end -0.299974 0.150114)
			(stroke
				(width 0.1)
				(type default)
			)
			(layer "B.Fab")
		)
		(fp_line
			(start 0.299974 0.150114)
			(end 0.299974 -0.150114)
			(stroke
				(width 0.1)
				(type default)
			)
			(layer "B.Fab")
		)
		(fp_line
			(start -0.299974 0.150114)
			(end 0.299974 0.150114)
			(stroke
				(width 0.1)
				(type default)
			)
			(layer "B.Fab")
		)
		(pad "1" smd rect
			(at 0.2667 0 270)
			(size 0.3048 0.381)
			(layers "B.Cu" "B.Mask" "B.Paste")
			(net "P0V8_SERDES_VDDA_PEX3")
		)
		(pad "2" smd rect
			(at -0.2667 0 270)
			(size 0.3048 0.381)
			(layers "B.Cu" "B.Mask" "B.Paste")
			(net "GND")
		)
	)
	(footprint ""
		(layer "B.Cu")
		(at 414.599882 -288.299906 90)
		(property "Reference" "C3445"
			(at 0 0 90)
			(layer "B.SilkS")
			(hide yes)
			(effects
				(font
					(size 1.27 1.27)
				)
				(justify mirror)
			)
		)
		(property "Value" ""
			(at 0 0 90)
			(layer "B.Fab")
			(effects
				(font
					(size 1.27 1.27)
				)
				(justify mirror)
			)
		)
		(duplicate_pad_numbers_are_jumpers no)
		(fp_line
			(start 0.299974 -0.150114)
			(end -0.299974 -0.150114)
			(stroke
				(width 0.1)
				(type default)
			)
			(layer "B.Fab")
		)
		(fp_line
			(start -0.299974 -0.150114)
			(end -0.299974 0.150114)
			(stroke
				(width 0.1)
				(type default)
			)
			(layer "B.Fab")
		)
		(fp_line
			(start 0.299974 0.150114)
			(end 0.299974 -0.150114)
			(stroke
				(width 0.1)
				(type default)
			)
			(layer "B.Fab")
		)
		(fp_line
			(start -0.299974 0.150114)
			(end 0.299974 0.150114)
			(stroke
				(width 0.1)
				(type default)
			)
			(layer "B.Fab")
		)
		(pad "1" smd rect
			(at 0.2667 0 270)
			(size 0.3048 0.381)
			(layers "B.Cu" "B.Mask" "B.Paste")
			(net "P1V25_PEX3")
		)
		(pad "2" smd rect
			(at -0.2667 0 270)
			(size 0.3048 0.381)
			(layers "B.Cu" "B.Mask" "B.Paste")
			(net "GND")
		)
	)
	(footprint ""
		(layer "B.Cu")
		(at 404.149814 -299.699934 -90)
		(property "Reference" "C1998"
			(at 0 0 90)
			(layer "B.SilkS")
			(hide yes)
			(effects
				(font
					(size 1.27 1.27)
				)
				(justify mirror)
			)
		)
		(property "Value" ""
			(at 0 0 90)
			(layer "B.Fab")
			(effects
				(font
					(size 1.27 1.27)
				)
				(justify mirror)
			)
		)
		(duplicate_pad_numbers_are_jumpers no)
		(fp_line
			(start -0.299974 0.150114)
			(end 0.299974 0.150114)
			(stroke
				(width 0.1)
				(type default)
			)
			(layer "B.Fab")
		)
		(fp_line
			(start 0.299974 0.150114)
			(end 0.299974 -0.150114)
			(stroke
				(width 0.1)
				(type default)
			)
			(layer "B.Fab")
		)
		(fp_line
			(start -0.299974 -0.150114)
			(end -0.299974 0.150114)
			(stroke
				(width 0.1)
				(type default)
			)
			(layer "B.Fab")
		)
		(fp_line
			(start 0.299974 -0.150114)
			(end -0.299974 -0.150114)
			(stroke
				(width 0.1)
				(type default)
			)
			(layer "B.Fab")
		)
		(pad "1" smd rect
			(at 0.2667 0 90)
			(size 0.3048 0.381)
			(layers "B.Cu" "B.Mask" "B.Paste")
			(net "P0V8_SERDES_VDDA_PEX3")
		)
		(pad "2" smd rect
			(at -0.2667 0 90)
			(size 0.3048 0.381)
			(layers "B.Cu" "B.Mask" "B.Paste")
			(net "GND")
		)
	)
	(footprint ""
		(layer "B.Cu")
		(at 328.106024 10.656824 180)
		(property "Reference" "DE16T_1"
			(at -2.805176 -3.009646 0)
			(unlocked yes)
			(layer "B.SilkS")
			(effects
				(font
					(size 0.7874 0.5842)
					(thickness 0.1524)
				)
				(justify left mirror)
			)
		)
		(property "Value" ""
			(at 0 0 0)
			(layer "B.Fab")
			(effects
				(font
					(size 1.27 1.27)
				)
				(justify mirror)
			)
		)
		(duplicate_pad_numbers_are_jumpers no)
		(fp_line
			(start 1.2192 2.1082)
			(end 1.2192 -2.1082)
			(stroke
				(width 0.1524)
				(type default)
			)
			(layer "B.SilkS")
		)
		(fp_line
			(start 1.2192 -2.1082)
			(end -1.2192 -2.1082)
			(stroke
				(width 0.1524)
				(type default)
			)
			(layer "B.SilkS")
		)
		(fp_line
			(start -1.2192 2.1082)
			(end 1.2192 2.1082)
			(stroke
				(width 0.1524)
				(type default)
			)
			(layer "B.SilkS")
		)
		(fp_line
			(start -1.2192 -2.1082)
			(end -1.2192 2.1082)
			(stroke
				(width 0.1524)
				(type default)
			)
			(layer "B.SilkS")
		)
		(pad "" np_thru_hole circle
			(at -3.4671 -1.27 90)
			(size 1.0414 1.0414)
			(drill 1.0414)
			(layers "*.Cu" "*.Mask")
			(clearance 0.381)
			(thermal_gap 0.381)
		)
		(pad "" np_thru_hole circle
			(at -3.4671 1.27 90)
			(size 1.0414 1.0414)
			(drill 1.0414)
			(layers "*.Cu" "*.Mask")
			(clearance 0.381)
			(thermal_gap 0.381)
		)
		(pad "" np_thru_hole circle
			(at 2.8829 -1.27 90)
			(size 1.0414 1.0414)
			(drill 1.0414)
			(layers "*.Cu" "*.Mask")
			(clearance 0.381)
			(thermal_gap 0.381)
		)
		(pad "" np_thru_hole circle
			(at 2.8829 1.27 90)
			(size 1.0414 1.0414)
			(drill 1.0414)
			(layers "*.Cu" "*.Mask")
			(clearance 0.381)
			(thermal_gap 0.381)
		)
		(pad "1" smd rect
			(at -0.8255 -0.249936 90)
			(size 0.3048 0.508)
			(layers "B.Cu" "B.Mask" "B.Paste")
			(net "85_10INCH_IN4_DP")
		)
		(pad "2" smd rect
			(at -0.8255 0.249936 90)
			(size 0.3048 0.508)
			(layers "B.Cu" "B.Mask" "B.Paste")
			(net "85_10INCH_IN4_DN")
		)
		(pad "3" smd circle
			(at 0 0)
			(size 0 0)
			(layers "B.Cu" "B.Mask" "B.Paste")
			(net "COUPON_GND2")
		)
		(zone
			(layers "F.Cu" "B.Cu" "In1.Cu" "In2.Cu" "In3.Cu" "In4.Cu" "In5.Cu" "In6.Cu"
				"In7.Cu" "In8.Cu" "In9.Cu" "In10.Cu" "In11.Cu" "In12.Cu" "In13.Cu" "In14.Cu"
				"In15.Cu" "In16.Cu"
			)
			(hatch none 0.5)
			(connect_pads
				(clearance 0)
			)
			(min_thickness 0.25)
			(keepout
				(tracks not_allowed)
				(vias allowed)
				(pads allowed)
				(copperpour not_allowed)
				(footprints allowed)
			)
			(placement
				(enabled no)
				(sheetname "")
			)
			(fill
				(thermal_gap 0.5)
				(thermal_bridge_width 0.5)
				(island_removal_mode 0)
			)
			(polygon
				(pts
					(arc
						(start 326.150224 9.386824)
						(mid 324.296024 9.386824)
						(end 326.150224 9.386824)
					)
				)
			)
		)
		(zone
			(layers "F.Cu" "B.Cu" "In1.Cu" "In2.Cu" "In3.Cu" "In4.Cu" "In5.Cu" "In6.Cu"
				"In7.Cu" "In8.Cu" "In9.Cu" "In10.Cu" "In11.Cu" "In12.Cu" "In13.Cu" "In14.Cu"
				"In15.Cu" "In16.Cu"
			)
			(hatch none 0.5)
			(connect_pads
				(clearance 0)
			)
			(min_thickness 0.25)
			(keepout
				(tracks not_allowed)
				(vias allowed)
				(pads allowed)
				(copperpour not_allowed)
				(footprints allowed)
			)
			(placement
				(enabled no)
				(sheetname "")
			)
			(fill
				(thermal_gap 0.5)
				(thermal_bridge_width 0.5)
				(island_removal_mode 0)
			)
			(polygon
				(pts
					(arc
						(start 326.150224 11.926824)
						(mid 324.296024 11.926824)
						(end 326.150224 11.926824)
					)
				)
			)
		)
		(zone
			(layers "F.Cu" "B.Cu" "In1.Cu" "In2.Cu" "In3.Cu" "In4.Cu" "In5.Cu" "In6.Cu"
				"In7.Cu" "In8.Cu" "In9.Cu" "In10.Cu" "In11.Cu" "In12.Cu" "In13.Cu" "In14.Cu"
				"In15.Cu" "In16.Cu"
			)
			(hatch none 0.5)
			(connect_pads
				(clearance 0)
			)
			(min_thickness 0.25)
			(keepout
				(tracks not_allowed)
				(vias allowed)
				(pads allowed)
				(copperpour not_allowed)
				(footprints allowed)
			)
			(placement
				(enabled no)
				(sheetname "")
			)
			(fill
				(thermal_gap 0.5)
				(thermal_bridge_width 0.5)
				(island_removal_mode 0)
			)
			(polygon
				(pts
					(arc
						(start 332.500224 9.386824)
						(mid 330.646024 9.386824)
						(end 332.500224 9.386824)
					)
				)
			)
		)
		(zone
			(layers "F.Cu" "B.Cu" "In1.Cu" "In2.Cu" "In3.Cu" "In4.Cu" "In5.Cu" "In6.Cu"
				"In7.Cu" "In8.Cu" "In9.Cu" "In10.Cu" "In11.Cu" "In12.Cu" "In13.Cu" "In14.Cu"
				"In15.Cu" "In16.Cu"
			)
			(hatch none 0.5)
			(connect_pads
				(clearance 0)
			)
			(min_thickness 0.25)
			(keepout
				(tracks not_allowed)
				(vias allowed)
				(pads allowed)
				(copperpour not_allowed)
				(footprints allowed)
			)
			(placement
				(enabled no)
				(sheetname "")
			)
			(fill
				(thermal_gap 0.5)
				(thermal_bridge_width 0.5)
				(island_removal_mode 0)
			)
			(polygon
				(pts
					(arc
						(start 332.500224 11.926824)
						(mid 330.646024 11.926824)
						(end 332.500224 11.926824)
					)
				)
			)
		)
		(zone
			(layer "B.Cu")
			(hatch none 0.5)
			(connect_pads
				(clearance 0)
			)
			(min_thickness 0.25)
			(keepout
				(tracks not_allowed)
				(vias allowed)
				(pads allowed)
				(copperpour not_allowed)
				(footprints allowed)
			)
			(placement
				(enabled no)
				(sheetname "")
			)
			(fill
				(thermal_gap 0.5)
				(thermal_bridge_width 0.5)
				(island_removal_mode 0)
			)
			(polygon
				(pts
					(xy 329.223624 11.205464) (xy 329.223624 11.10996) (xy 328.626724 11.10996) (xy 328.626724 10.70356)
					(xy 329.223624 10.70356) (xy 329.223624 10.610088) (xy 328.626724 10.610088) (xy 328.626724 10.203688)
					(xy 329.223624 10.203688) (xy 329.223624 10.108184) (xy 328.525124 10.108184) (xy 328.525124 11.205464)
				)
			)
		)
	)
	(footprint ""
		(layer "B.Cu")
		(at 348.98838 -317.6778 180)
		(property "Reference" "C4323"
			(at 0 0 0)
			(layer "B.SilkS")
			(hide yes)
			(effects
				(font
					(size 1.27 1.27)
				)
				(justify mirror)
			)
		)
		(property "Value" ""
			(at 0 0 0)
			(layer "B.Fab")
			(effects
				(font
					(size 1.27 1.27)
				)
				(justify mirror)
			)
		)
		(duplicate_pad_numbers_are_jumpers no)
		(fp_line
			(start 0.299974 0.150114)
			(end 0.299974 -0.150114)
			(stroke
				(width 0.1)
				(type default)
			)
			(layer "B.Fab")
		)
		(fp_line
			(start 0.299974 -0.150114)
			(end -0.299974 -0.150114)
			(stroke
				(width 0.1)
				(type default)
			)
			(layer "B.Fab")
		)
		(fp_line
			(start -0.299974 0.150114)
			(end 0.299974 0.150114)
			(stroke
				(width 0.1)
				(type default)
			)
			(layer "B.Fab")
		)
		(fp_line
			(start -0.299974 -0.150114)
			(end -0.299974 0.150114)
			(stroke
				(width 0.1)
				(type default)
			)
			(layer "B.Fab")
		)
		(pad "1" smd rect
			(at 0.2667 0)
			(size 0.3048 0.381)
			(layers "B.Cu" "B.Mask" "B.Paste")
			(net "P0V8_SERDES_VDDA_PEX2")
		)
		(pad "2" smd rect
			(at -0.2667 0)
			(size 0.3048 0.381)
			(layers "B.Cu" "B.Mask" "B.Paste")
			(net "GND")
		)
	)
)
